# T6G (Grand Teton) — schematic netlist excerpt (pin names and nets, part order shuffled) for the footprints in the layout excerpt that follows; sources: Cadence DE-HDL packaged netlist, KiCad conversion of 04192023_DAF0TMB3IC0_F0TG_MB_C_brd_V02_OCP.brd

PC819  Q_CAP  0.1UF 25V 10% X7R  pkg 0402  page 364 : A = P0V9_RETIMER_CPU1_VINSEN ; B = GND
C820  Q_CAP_DIFFBUS  DIFF BUS_0.22UF 6.3V 20% X6S  pkg C0201  page 65 : \1\ = P5E_CPU1_P0_TX_C_DN<8> ; \2\ = P5E_CPU1_P0_TX_DN<8>
PC8002  Q_CAP  22UF 16V 20% X6S  pkg C0805  page 209 : A = SW_P12V_AUX_PVDD18_S5_P0_FLT ; B = GND

(kicad_pcb
	(version 20260206)
	(generator "pcbnew")
	(generator_version "10.0")
	(general
		(thickness 1.6)
		(legacy_teardrops no)
	)
	(paper "A4")
	(title_block
		(title "04192023_DAF0TMB3IC0_F0TG_MB_C_brd_V02_OCP.brd")
		(comment 1 "Grand Teton / footprints 3366-3369 of 8354")
	)
	(layers
		(0 "F.Cu" signal "TOP")
		(4 "In1.Cu" signal "GND")
		(6 "In2.Cu" signal "IN1")
		(8 "In3.Cu" signal "GND1")
		(10 "In4.Cu" signal "IN2")
		(12 "In5.Cu" signal "GND2")
		(14 "In6.Cu" signal "IN3")
		(16 "In7.Cu" signal "GND3")
		(18 "In8.Cu" signal "VCC")
		(20 "In9.Cu" signal "VCC1")
		(22 "In10.Cu" signal "GND4")
		(24 "In11.Cu" signal "IN4")
		(26 "In12.Cu" signal "GND5")
		(28 "In13.Cu" signal "IN5")
		(30 "In14.Cu" signal "GND6")
		(32 "In15.Cu" signal "IN6")
		(34 "In16.Cu" signal "GND7")
		(2 "B.Cu" signal "BOTTOM")
		(9 "F.Adhes" user "F.Adhesive")
		(11 "B.Adhes" user "B.Adhesive")
		(13 "F.Paste" user "Package Geometry/Pastemask Top")
		(15 "B.Paste" user "Package Geometry/Pastemask Bottom")
		(5 "F.SilkS" user "Ref Des/Silkscreen Top")
		(7 "B.SilkS" user "Ref Des/Silkscreen Bottom")
		(1 "F.Mask" user "Board Geometry/Soldermask Top")
		(3 "B.Mask" user "Board Geometry/Soldermask Bottom")
		(17 "Dwgs.User" user "User.Drawings")
		(19 "Cmts.User" user "User.Comments")
		(21 "Eco1.User" user "User.Eco1")
		(23 "Eco2.User" user "User.Eco2")
		(25 "Edge.Cuts" user "Board Geometry/Outline")
		(27 "Margin" user)
		(31 "F.CrtYd" user "Package Geometry/Place Bound Top")
		(29 "B.CrtYd" user "Package Geometry/Place Bound Bottom")
		(35 "F.Fab" user "Ref Des/Assembly Top")
		(33 "B.Fab" user "Ref Des/Assembly Bottom")
	)
	(footprint ""
		(layer "F.Cu")
		(at 336.172556 -131.99745)
		(property "Reference" "PC8002"
			(at 0 0 0)
			(layer "F.SilkS")
			(hide yes)
			(effects
				(font
					(size 1.27 1.27)
				)
			)
		)
		(property "Value" ""
			(at 0 0 0)
			(layer "F.Fab")
			(effects
				(font
					(size 1.27 1.27)
				)
			)
		)
		(duplicate_pad_numbers_are_jumpers no)
		(fp_line
			(start -1.524 -0.762)
			(end 1.524 -0.762)
			(stroke
				(width 0.1524)
				(type default)
			)
			(layer "F.SilkS")
		)
		(fp_line
			(start -1.524 0.762)
			(end -1.524 -0.762)
			(stroke
				(width 0.1524)
				(type default)
			)
			(layer "F.SilkS")
		)
		(fp_line
			(start 1.524 -0.762)
			(end 1.524 0.762)
			(stroke
				(width 0.1524)
				(type default)
			)
			(layer "F.SilkS")
		)
		(fp_line
			(start 1.524 0.762)
			(end -1.524 0.762)
			(stroke
				(width 0.1524)
				(type default)
			)
			(layer "F.SilkS")
		)
		(fp_line
			(start -1.1049 -0.724916)
			(end -1.1049 0.724916)
			(stroke
				(width 0.1)
				(type default)
			)
			(layer "F.Fab")
		)
		(fp_line
			(start -1.1049 0.724916)
			(end 1.1049 0.724916)
			(stroke
				(width 0.1)
				(type default)
			)
			(layer "F.Fab")
		)
		(fp_line
			(start 1.1049 -0.724916)
			(end -1.1049 -0.724916)
			(stroke
				(width 0.1)
				(type default)
			)
			(layer "F.Fab")
		)
		(fp_line
			(start 1.1049 0.724916)
			(end 1.1049 -0.724916)
			(stroke
				(width 0.1)
				(type default)
			)
			(layer "F.Fab")
		)
		(pad "1" smd rect
			(at -0.889 0 180)
			(size 1.016 1.27)
			(layers "F.Cu" "F.Mask" "F.Paste")
			(net "SW_P12V_AUX_PVDD18_S5_P0_FLT")
		)
		(pad "2" smd rect
			(at 0.889 0 180)
			(size 1.016 1.27)
			(layers "F.Cu" "F.Mask" "F.Paste")
			(net "GND")
		)
	)
	(footprint ""
		(layer "F.Cu")
		(at 5.260086 -35.495484 180)
		(property "Reference" ""
			(at 0 0 180)
			(layer "F.SilkS")
			(hide yes)
			(effects
				(font
					(size 1.27 1.27)
				)
			)
		)
		(property "Value" ""
			(at 0 0 180)
			(layer "F.Fab")
			(effects
				(font
					(size 1.27 1.27)
				)
			)
		)
		(duplicate_pad_numbers_are_jumpers no)
		(pad "1" smd circle
			(at 0 0 180)
			(size 0.9906 0.9906)
			(layers "F.Cu" "F.Mask" "F.Paste")
			(net "Net_10726")
		)
		(zone
			(layer "F.Cu")
			(hatch none 0.5)
			(connect_pads
				(clearance 0)
			)
			(min_thickness 0.25)
			(keepout
				(tracks not_allowed)
				(vias allowed)
				(pads allowed)
				(copperpour not_allowed)
				(footprints allowed)
			)
			(placement
				(enabled no)
				(sheetname "")
			)
			(fill
				(thermal_gap 0.5)
				(thermal_bridge_width 0.5)
				(island_removal_mode 0)
			)
			(polygon
				(pts
					(arc
						(start 6.885686 -35.495484)
						(mid 3.634486 -35.495484)
						(end 6.885686 -35.495484)
					)
				)
			)
		)
	)
	(footprint ""
		(layer "F.Cu")
		(at 10.066782 -408.405584 180)
		(property "Reference" "PC819"
			(at 0 0 180)
			(layer "F.SilkS")
			(hide yes)
			(effects
				(font
					(size 1.27 1.27)
				)
			)
		)
		(property "Value" ""
			(at 0 0 180)
			(layer "F.Fab")
			(effects
				(font
					(size 1.27 1.27)
				)
			)
		)
		(duplicate_pad_numbers_are_jumpers no)
		(fp_line
			(start 0.7874 0.4064)
			(end -0.7874 0.4064)
			(stroke
				(width 0.1524)
				(type default)
			)
			(layer "F.SilkS")
		)
		(fp_line
			(start 0.7874 -0.4064)
			(end 0.7874 0.4064)
			(stroke
				(width 0.1524)
				(type default)
			)
			(layer "F.SilkS")
		)
		(fp_line
			(start -0.7874 0.4064)
			(end -0.7874 -0.4064)
			(stroke
				(width 0.1524)
				(type default)
			)
			(layer "F.SilkS")
		)
		(fp_line
			(start -0.7874 -0.4064)
			(end 0.7874 -0.4064)
			(stroke
				(width 0.1524)
				(type default)
			)
			(layer "F.SilkS")
		)
		(fp_line
			(start 0.67945 0.3048)
			(end 0.120396 0.3048)
			(stroke
				(width 0.1)
				(type default)
			)
			(layer "F.Fab")
		)
		(fp_line
			(start 0.67945 -0.3048)
			(end 0.67945 0.3048)
			(stroke
				(width 0.1)
				(type default)
			)
			(layer "F.Fab")
		)
		(fp_line
			(start 0.12065 -0.2794)
			(end 0.12065 -0.3048)
			(stroke
				(width 0.1)
				(type default)
			)
			(layer "F.Fab")
		)
		(fp_line
			(start 0.12065 -0.3048)
			(end 0.67945 -0.3048)
			(stroke
				(width 0.1)
				(type default)
			)
			(layer "F.Fab")
		)
		(fp_line
			(start 0.120396 0.3048)
			(end 0.120396 0.2794)
			(stroke
				(width 0.1)
				(type default)
			)
			(layer "F.Fab")
		)
		(fp_line
			(start 0.120396 0.2794)
			(end -0.12065 0.2794)
			(stroke
				(width 0.1)
				(type default)
			)
			(layer "F.Fab")
		)
		(fp_line
			(start -0.12065 0.3048)
			(end -0.67945 0.3048)
			(stroke
				(width 0.1)
				(type default)
			)
			(layer "F.Fab")
		)
		(fp_line
			(start -0.12065 0.2794)
			(end -0.12065 0.3048)
			(stroke
				(width 0.1)
				(type default)
			)
			(layer "F.Fab")
		)
		(fp_line
			(start -0.12065 -0.2794)
			(end 0.12065 -0.2794)
			(stroke
				(width 0.1)
				(type default)
			)
			(layer "F.Fab")
		)
		(fp_line
			(start -0.12065 -0.305054)
			(end -0.12065 -0.2794)
			(stroke
				(width 0.1)
				(type default)
			)
			(layer "F.Fab")
		)
		(fp_line
			(start -0.67945 0.3048)
			(end -0.67945 -0.305054)
			(stroke
				(width 0.1)
				(type default)
			)
			(layer "F.Fab")
		)
		(fp_line
			(start -0.67945 -0.305054)
			(end -0.12065 -0.305054)
			(stroke
				(width 0.1)
				(type default)
			)
			(layer "F.Fab")
		)
		(pad "1" smd circle
			(at -0.40005 0 180)
			(size 0 0)
			(layers "F.Cu" "F.Mask" "F.Paste")
			(net "P0V9_RETIMER_CPU1_VINSEN")
		)
		(pad "2" smd circle
			(at 0.40005 0 180)
			(size 0 0)
			(layers "F.Cu" "F.Mask" "F.Paste")
			(net "GND")
		)
	)
	(footprint ""
		(layer "F.Cu")
		(at 57.518554 -373.03583 -90)
		(property "Reference" "C820"
			(at 0 0 270)
			(layer "F.SilkS")
			(hide yes)
			(effects
				(font
					(size 1.27 1.27)
				)
			)
		)
		(property "Value" ""
			(at 0 0 270)
			(layer "F.Fab")
			(effects
				(font
					(size 1.27 1.27)
				)
			)
		)
		(duplicate_pad_numbers_are_jumpers no)
		(fp_line
			(start -0.299974 0.150114)
			(end -0.299974 -0.150114)
			(stroke
				(width 0.1)
				(type default)
			)
			(layer "F.Fab")
		)
		(fp_line
			(start 0.299974 0.150114)
			(end -0.299974 0.150114)
			(stroke
				(width 0.1)
				(type default)
			)
			(layer "F.Fab")
		)
		(fp_line
			(start -0.299974 -0.150114)
			(end 0.299974 -0.150114)
			(stroke
				(width 0.1)
				(type default)
			)
			(layer "F.Fab")
		)
		(fp_line
			(start 0.299974 -0.150114)
			(end 0.299974 0.150114)
			(stroke
				(width 0.1)
				(type default)
			)
			(layer "F.Fab")
		)
		(pad "1" smd rect
			(at -0.2667 0 270)
			(size 0.3048 0.381)
			(layers "F.Cu" "F.Mask" "F.Paste")
			(net "P5E_CPU1_P0_TX_C_DN<8>")
		)
		(pad "2" smd rect
			(at 0.2667 0 270)
			(size 0.3048 0.381)
			(layers "F.Cu" "F.Mask" "F.Paste")
			(net "P5E_CPU1_P0_TX_DN<8>")
		)
	)
)
